(kicad_pcb
	(version 20260206)
	(generator "pcbnew")
	(generator_version "10.0")
	(general
		(thickness 1.6)
		(legacy_teardrops no)
	)
	(paper "A4")
	(title_block
		(title "01162023_DA0F0TEBIF0_F0T_Expander_BD_F_brd_V02_OCP.brd")
		(comment 1 "Grand Teton / footprints 2263-2269 of 9728")
	)
	(layers
		(0 "F.Cu" signal "TOP")
		(4 "In1.Cu" signal "GND")
		(6 "In2.Cu" signal "VCC")
		(8 "In3.Cu" signal "VCC1")
		(10 "In4.Cu" signal "GND1")
		(12 "In5.Cu" signal "IN1")
		(14 "In6.Cu" signal "GND2")
		(16 "In7.Cu" signal "IN2")
		(18 "In8.Cu" signal "GND3")
		(20 "In9.Cu" signal "IN3")
		(22 "In10.Cu" signal "GND4")
		(24 "In11.Cu" signal "IN4")
		(26 "In12.Cu" signal "GND5")
		(28 "In13.Cu" signal "IN5")
		(30 "In14.Cu" signal "GND6")
		(32 "In15.Cu" signal "IN6")
		(34 "In16.Cu" signal "GND7")
		(2 "B.Cu" signal "BOTTOM")
		(9 "F.Adhes" user "F.Adhesive")
		(11 "B.Adhes" user "B.Adhesive")
		(13 "F.Paste" user "Package Geometry/Pastemask Top")
		(15 "B.Paste" user "Package Geometry/Pastemask Bottom")
		(5 "F.SilkS" user "Ref Des/Silkscreen Top")
		(7 "B.SilkS" user "Ref Des/Silkscreen Bottom")
		(1 "F.Mask" user "Board Geometry/Soldermask Top")
		(3 "B.Mask" user "Board Geometry/Soldermask Bottom")
		(17 "Dwgs.User" user "User.Drawings")
		(19 "Cmts.User" user "User.Comments")
		(21 "Eco1.User" user "User.Eco1")
		(23 "Eco2.User" user "User.Eco2")
		(25 "Edge.Cuts" user "Board Geometry/Outline")
		(27 "Margin" user)
		(31 "F.CrtYd" user "Package Geometry/Place Bound Top")
		(29 "B.CrtYd" user "Package Geometry/Place Bound Bottom")
		(35 "F.Fab" user "Ref Des/Assembly Top")
		(33 "B.Fab" user "Ref Des/Assembly Bottom")
	)
	(footprint ""
		(layer "F.Cu")
		(at 327.533 -216.281 180)
		(property "Reference" "R4156"
			(at 0 0 180)
			(layer "F.SilkS")
			(hide yes)
			(effects
				(font
					(size 1.27 1.27)
				)
			)
		)
		(property "Value" ""
			(at 0 0 180)
			(layer "F.Fab")
			(effects
				(font
					(size 1.27 1.27)
				)
			)
		)
		(duplicate_pad_numbers_are_jumpers no)
		(fp_line
			(start 0.7874 0.4064)
			(end -0.7874 0.4064)
			(stroke
				(width 0.1524)
				(type default)
			)
			(layer "F.SilkS")
		)
		(fp_line
			(start 0.7874 -0.4064)
			(end 0.7874 0.4064)
			(stroke
				(width 0.1524)
				(type default)
			)
			(layer "F.SilkS")
		)
		(fp_line
			(start -0.7874 0.4064)
			(end -0.7874 -0.4064)
			(stroke
				(width 0.1524)
				(type default)
			)
			(layer "F.SilkS")
		)
		(fp_line
			(start -0.7874 -0.4064)
			(end 0.7874 -0.4064)
			(stroke
				(width 0.1524)
				(type default)
			)
			(layer "F.SilkS")
		)
		(fp_line
			(start 0.67945 0.3048)
			(end 0.120396 0.3048)
			(stroke
				(width 0.1)
				(type default)
			)
			(layer "F.Fab")
		)
		(fp_line
			(start 0.67945 -0.3048)
			(end 0.67945 0.3048)
			(stroke
				(width 0.1)
				(type default)
			)
			(layer "F.Fab")
		)
		(fp_line
			(start 0.12065 -0.2794)
			(end 0.12065 -0.3048)
			(stroke
				(width 0.1)
				(type default)
			)
			(layer "F.Fab")
		)
		(fp_line
			(start 0.12065 -0.3048)
			(end 0.67945 -0.3048)
			(stroke
				(width 0.1)
				(type default)
			)
			(layer "F.Fab")
		)
		(fp_line
			(start 0.120396 0.3048)
			(end 0.120396 0.2794)
			(stroke
				(width 0.1)
				(type default)
			)
			(layer "F.Fab")
		)
		(fp_line
			(start 0.120396 0.2794)
			(end -0.12065 0.2794)
			(stroke
				(width 0.1)
				(type default)
			)
			(layer "F.Fab")
		)
		(fp_line
			(start -0.12065 0.3048)
			(end -0.67945 0.3048)
			(stroke
				(width 0.1)
				(type default)
			)
			(layer "F.Fab")
		)
		(fp_line
			(start -0.12065 0.2794)
			(end -0.12065 0.3048)
			(stroke
				(width 0.1)
				(type default)
			)
			(layer "F.Fab")
		)
		(fp_line
			(start -0.12065 -0.2794)
			(end 0.12065 -0.2794)
			(stroke
				(width 0.1)
				(type default)
			)
			(layer "F.Fab")
		)
		(fp_line
			(start -0.12065 -0.305054)
			(end -0.12065 -0.2794)
			(stroke
				(width 0.1)
				(type default)
			)
			(layer "F.Fab")
		)
		(fp_line
			(start -0.67945 0.3048)
			(end -0.67945 -0.305054)
			(stroke
				(width 0.1)
				(type default)
			)
			(layer "F.Fab")
		)
		(fp_line
			(start -0.67945 -0.305054)
			(end -0.12065 -0.305054)
			(stroke
				(width 0.1)
				(type default)
			)
			(layer "F.Fab")
		)
		(pad "1" smd circle
			(at -0.40005 0 180)
			(size 0 0)
			(layers "F.Cu" "F.Mask" "F.Paste")
			(net "PRSNT_SSD9_FPGA_N")
		)
		(pad "2" smd circle
			(at 0.40005 0 180)
			(size 0 0)
			(layers "F.Cu" "F.Mask" "F.Paste")
			(net "PRSNT_SSD9_FPGA_R_N")
		)
	)
	(footprint ""
		(layer "F.Cu")
		(at 122.29719 -110.722918 90)
		(property "Reference" "R5826"
			(at 0 0 90)
			(layer "F.SilkS")
			(hide yes)
			(effects
				(font
					(size 1.27 1.27)
				)
			)
		)
		(property "Value" ""
			(at 0 0 90)
			(layer "F.Fab")
			(effects
				(font
					(size 1.27 1.27)
				)
			)
		)
		(duplicate_pad_numbers_are_jumpers no)
		(fp_line
			(start 0.7874 -0.4064)
			(end 0.7874 0.4064)
			(stroke
				(width 0.1524)
				(type default)
			)
			(layer "F.SilkS")
		)
		(fp_line
			(start -0.7874 -0.4064)
			(end 0.7874 -0.4064)
			(stroke
				(width 0.1524)
				(type default)
			)
			(layer "F.SilkS")
		)
		(fp_line
			(start 0.7874 0.4064)
			(end -0.7874 0.4064)
			(stroke
				(width 0.1524)
				(type default)
			)
			(layer "F.SilkS")
		)
		(fp_line
			(start -0.7874 0.4064)
			(end -0.7874 -0.4064)
			(stroke
				(width 0.1524)
				(type default)
			)
			(layer "F.SilkS")
		)
		(fp_line
			(start -0.12065 -0.305054)
			(end -0.12065 -0.2794)
			(stroke
				(width 0.1)
				(type default)
			)
			(layer "F.Fab")
		)
		(fp_line
			(start -0.67945 -0.305054)
			(end -0.12065 -0.305054)
			(stroke
				(width 0.1)
				(type default)
			)
			(layer "F.Fab")
		)
		(fp_line
			(start 0.67945 -0.3048)
			(end 0.67945 0.3048)
			(stroke
				(width 0.1)
				(type default)
			)
			(layer "F.Fab")
		)
		(fp_line
			(start 0.12065 -0.3048)
			(end 0.67945 -0.3048)
			(stroke
				(width 0.1)
				(type default)
			)
			(layer "F.Fab")
		)
		(fp_line
			(start 0.12065 -0.2794)
			(end 0.12065 -0.3048)
			(stroke
				(width 0.1)
				(type default)
			)
			(layer "F.Fab")
		)
		(fp_line
			(start -0.12065 -0.2794)
			(end 0.12065 -0.2794)
			(stroke
				(width 0.1)
				(type default)
			)
			(layer "F.Fab")
		)
		(fp_line
			(start 0.120396 0.2794)
			(end -0.12065 0.2794)
			(stroke
				(width 0.1)
				(type default)
			)
			(layer "F.Fab")
		)
		(fp_line
			(start -0.12065 0.2794)
			(end -0.12065 0.3048)
			(stroke
				(width 0.1)
				(type default)
			)
			(layer "F.Fab")
		)
		(fp_line
			(start 0.67945 0.3048)
			(end 0.120396 0.3048)
			(stroke
				(width 0.1)
				(type default)
			)
			(layer "F.Fab")
		)
		(fp_line
			(start 0.120396 0.3048)
			(end 0.120396 0.2794)
			(stroke
				(width 0.1)
				(type default)
			)
			(layer "F.Fab")
		)
		(fp_line
			(start -0.12065 0.3048)
			(end -0.67945 0.3048)
			(stroke
				(width 0.1)
				(type default)
			)
			(layer "F.Fab")
		)
		(fp_line
			(start -0.67945 0.3048)
			(end -0.67945 -0.305054)
			(stroke
				(width 0.1)
				(type default)
			)
			(layer "F.Fab")
		)
		(pad "1" smd circle
			(at -0.40005 0 90)
			(size 0 0)
			(layers "F.Cu" "F.Mask" "F.Paste")
			(net "PWRGD_P3V3_D")
		)
		(pad "2" smd circle
			(at 0.40005 0 90)
			(size 0 0)
			(layers "F.Cu" "F.Mask" "F.Paste")
			(net "PWRGD_P3V3_R")
		)
	)
	(footprint ""
		(layer "F.Cu")
		(at 337.752944 -80.607662 90)
		(property "Reference" "R1173"
			(at 0 0 90)
			(layer "F.SilkS")
			(hide yes)
			(effects
				(font
					(size 1.27 1.27)
				)
			)
		)
		(property "Value" ""
			(at 0 0 90)
			(layer "F.Fab")
			(effects
				(font
					(size 1.27 1.27)
				)
			)
		)
		(duplicate_pad_numbers_are_jumpers no)
		(fp_line
			(start 0.7874 0.4064)
			(end -0.7874 0.4064)
			(stroke
				(width 0.1524)
				(type default)
			)
			(layer "F.SilkS")
		)
		(fp_line
			(start -0.12065 -0.305054)
			(end -0.12065 -0.2794)
			(stroke
				(width 0.1)
				(type default)
			)
			(layer "F.Fab")
		)
		(fp_line
			(start -0.67945 -0.305054)
			(end -0.12065 -0.305054)
			(stroke
				(width 0.1)
				(type default)
			)
			(layer "F.Fab")
		)
		(fp_line
			(start 0.67945 -0.3048)
			(end 0.67945 0.3048)
			(stroke
				(width 0.1)
				(type default)
			)
			(layer "F.Fab")
		)
		(fp_line
			(start 0.12065 -0.3048)
			(end 0.67945 -0.3048)
			(stroke
				(width 0.1)
				(type default)
			)
			(layer "F.Fab")
		)
		(fp_line
			(start 0.12065 -0.2794)
			(end 0.12065 -0.3048)
			(stroke
				(width 0.1)
				(type default)
			)
			(layer "F.Fab")
		)
		(fp_line
			(start -0.12065 -0.2794)
			(end 0.12065 -0.2794)
			(stroke
				(width 0.1)
				(type default)
			)
			(layer "F.Fab")
		)
		(fp_line
			(start 0.120396 0.2794)
			(end -0.12065 0.2794)
			(stroke
				(width 0.1)
				(type default)
			)
			(layer "F.Fab")
		)
		(fp_line
			(start -0.12065 0.2794)
			(end -0.12065 0.3048)
			(stroke
				(width 0.1)
				(type default)
			)
			(layer "F.Fab")
		)
		(fp_line
			(start 0.67945 0.3048)
			(end 0.120396 0.3048)
			(stroke
				(width 0.1)
				(type default)
			)
			(layer "F.Fab")
		)
		(fp_line
			(start 0.120396 0.3048)
			(end 0.120396 0.2794)
			(stroke
				(width 0.1)
				(type default)
			)
			(layer "F.Fab")
		)
		(fp_line
			(start -0.12065 0.3048)
			(end -0.67945 0.3048)
			(stroke
				(width 0.1)
				(type default)
			)
			(layer "F.Fab")
		)
		(fp_line
			(start -0.67945 0.3048)
			(end -0.67945 -0.305054)
			(stroke
				(width 0.1)
				(type default)
			)
			(layer "F.Fab")
		)
		(pad "1" smd circle
			(at -0.40005 0 90)
			(size 0 0)
			(layers "F.Cu" "F.Mask" "F.Paste")
			(net "CLK_100M_DB800ZL_SSD9_R_DN")
		)
		(pad "2" smd circle
			(at 0.40005 0 90)
			(size 0 0)
			(layers "F.Cu" "F.Mask" "F.Paste")
			(net "CLK_100M_DB800ZL_SSD9_DN")
		)
	)
	(footprint ""
		(layer "F.Cu")
		(at 17.337786 -268.134084)
		(property "Reference" "C4238"
			(at 0 0 0)
			(layer "F.SilkS")
			(hide yes)
			(effects
				(font
					(size 1.27 1.27)
				)
			)
		)
		(property "Value" ""
			(at 0 0 0)
			(layer "F.Fab")
			(effects
				(font
					(size 1.27 1.27)
				)
			)
		)
		(duplicate_pad_numbers_are_jumpers no)
		(fp_line
			(start -0.299974 -0.150114)
			(end 0.299974 -0.150114)
			(stroke
				(width 0.1)
				(type default)
			)
			(layer "F.Fab")
		)
		(fp_line
			(start -0.299974 0.150114)
			(end -0.299974 -0.150114)
			(stroke
				(width 0.1)
				(type default)
			)
			(layer "F.Fab")
		)
		(fp_line
			(start 0.299974 -0.150114)
			(end 0.299974 0.150114)
			(stroke
				(width 0.1)
				(type default)
			)
			(layer "F.Fab")
		)
		(fp_line
			(start 0.299974 0.150114)
			(end -0.299974 0.150114)
			(stroke
				(width 0.1)
				(type default)
			)
			(layer "F.Fab")
		)
		(pad "1" smd rect
			(at -0.2667 0)
			(size 0.3048 0.381)
			(layers "F.Cu" "F.Mask" "F.Paste")
			(net "P1V25_SERDES_VDDPLL_PEX0")
		)
		(pad "2" smd rect
			(at 0.2667 0)
			(size 0.3048 0.381)
			(layers "F.Cu" "F.Mask" "F.Paste")
			(net "GND")
		)
	)
	(footprint ""
		(layer "F.Cu")
		(at 100.868734 -237.306612 90)
		(property "Reference" "PC294"
			(at 0 0 90)
			(layer "F.SilkS")
			(hide yes)
			(effects
				(font
					(size 1.27 1.27)
				)
			)
		)
		(property "Value" ""
			(at 0 0 90)
			(layer "F.Fab")
			(effects
				(font
					(size 1.27 1.27)
				)
			)
		)
		(duplicate_pad_numbers_are_jumpers no)
		(fp_line
			(start 1.524 -0.762)
			(end 1.524 0.762)
			(stroke
				(width 0.1524)
				(type default)
			)
			(layer "F.SilkS")
		)
		(fp_line
			(start -1.524 -0.762)
			(end 1.524 -0.762)
			(stroke
				(width 0.1524)
				(type default)
			)
			(layer "F.SilkS")
		)
		(fp_line
			(start 1.524 0.762)
			(end -1.524 0.762)
			(stroke
				(width 0.1524)
				(type default)
			)
			(layer "F.SilkS")
		)
		(fp_line
			(start -1.524 0.762)
			(end -1.524 -0.762)
			(stroke
				(width 0.1524)
				(type default)
			)
			(layer "F.SilkS")
		)
		(fp_line
			(start 1.1049 -0.724916)
			(end -1.1049 -0.724916)
			(stroke
				(width 0.1)
				(type default)
			)
			(layer "F.Fab")
		)
		(fp_line
			(start -1.1049 -0.724916)
			(end -1.1049 0.724916)
			(stroke
				(width 0.1)
				(type default)
			)
			(layer "F.Fab")
		)
		(fp_line
			(start 1.1049 0.724916)
			(end 1.1049 -0.724916)
			(stroke
				(width 0.1)
				(type default)
			)
			(layer "F.Fab")
		)
		(fp_line
			(start -1.1049 0.724916)
			(end 1.1049 0.724916)
			(stroke
				(width 0.1)
				(type default)
			)
			(layer "F.Fab")
		)
		(pad "1" smd rect
			(at -0.889 0 270)
			(size 1.016 1.27)
			(layers "F.Cu" "F.Mask" "F.Paste")
			(net "P1V8_PEX_R")
		)
		(pad "2" smd rect
			(at 0.889 0 270)
			(size 1.016 1.27)
			(layers "F.Cu" "F.Mask" "F.Paste")
			(net "GND")
		)
	)
	(footprint ""
		(layer "F.Cu")
		(at 115.356386 -87.384382 180)
		(property "Reference" "R1147"
			(at 0 0 180)
			(layer "F.SilkS")
			(hide yes)
			(effects
				(font
					(size 1.27 1.27)
				)
			)
		)
		(property "Value" ""
			(at 0 0 180)
			(layer "F.Fab")
			(effects
				(font
					(size 1.27 1.27)
				)
			)
		)
		(duplicate_pad_numbers_are_jumpers no)
		(fp_line
			(start 0.7874 0.4064)
			(end -0.7874 0.4064)
			(stroke
				(width 0.1524)
				(type default)
			)
			(layer "F.SilkS")
		)
		(fp_line
			(start 0.67945 0.3048)
			(end 0.120396 0.3048)
			(stroke
				(width 0.1)
				(type default)
			)
			(layer "F.Fab")
		)
		(fp_line
			(start 0.67945 -0.3048)
			(end 0.67945 0.3048)
			(stroke
				(width 0.1)
				(type default)
			)
			(layer "F.Fab")
		)
		(fp_line
			(start 0.12065 -0.2794)
			(end 0.12065 -0.3048)
			(stroke
				(width 0.1)
				(type default)
			)
			(layer "F.Fab")
		)
		(fp_line
			(start 0.12065 -0.3048)
			(end 0.67945 -0.3048)
			(stroke
				(width 0.1)
				(type default)
			)
			(layer "F.Fab")
		)
		(fp_line
			(start 0.120396 0.3048)
			(end 0.120396 0.2794)
			(stroke
				(width 0.1)
				(type default)
			)
			(layer "F.Fab")
		)
		(fp_line
			(start 0.120396 0.2794)
			(end -0.12065 0.2794)
			(stroke
				(width 0.1)
				(type default)
			)
			(layer "F.Fab")
		)
		(fp_line
			(start -0.12065 0.3048)
			(end -0.67945 0.3048)
			(stroke
				(width 0.1)
				(type default)
			)
			(layer "F.Fab")
		)
		(fp_line
			(start -0.12065 0.2794)
			(end -0.12065 0.3048)
			(stroke
				(width 0.1)
				(type default)
			)
			(layer "F.Fab")
		)
		(fp_line
			(start -0.12065 -0.2794)
			(end 0.12065 -0.2794)
			(stroke
				(width 0.1)
				(type default)
			)
			(layer "F.Fab")
		)
		(fp_line
			(start -0.12065 -0.305054)
			(end -0.12065 -0.2794)
			(stroke
				(width 0.1)
				(type default)
			)
			(layer "F.Fab")
		)
		(fp_line
			(start -0.67945 0.3048)
			(end -0.67945 -0.305054)
			(stroke
				(width 0.1)
				(type default)
			)
			(layer "F.Fab")
		)
		(fp_line
			(start -0.67945 -0.305054)
			(end -0.12065 -0.305054)
			(stroke
				(width 0.1)
				(type default)
			)
			(layer "F.Fab")
		)
		(pad "1" smd circle
			(at -0.40005 0 180)
			(size 0 0)
			(layers "F.Cu" "F.Mask" "F.Paste")
			(net "CLK_100M_DB800ZL_SSD5_R_DN")
		)
		(pad "2" smd circle
			(at 0.40005 0 180)
			(size 0 0)
			(layers "F.Cu" "F.Mask" "F.Paste")
			(net "CLK_100M_DB800ZL_SSD5_DN")
		)
	)
	(footprint ""
		(layer "F.Cu")
		(at 219.202 -199.644 180)
		(property "Reference" "C2627"
			(at 0 0 180)
			(layer "F.SilkS")
			(hide yes)
			(effects
				(font
					(size 1.27 1.27)
				)
			)
		)
		(property "Value" ""
			(at 0 0 180)
			(layer "F.Fab")
			(effects
				(font
					(size 1.27 1.27)
				)
			)
		)
		(duplicate_pad_numbers_are_jumpers no)
		(fp_line
			(start 0.7874 0.4064)
			(end -0.7874 0.4064)
			(stroke
				(width 0.1524)
				(type default)
			)
			(layer "F.SilkS")
		)
		(fp_line
			(start 0.7874 -0.4064)
			(end 0.7874 0.4064)
			(stroke
				(width 0.1524)
				(type default)
			)
			(layer "F.SilkS")
		)
		(fp_line
			(start -0.7874 0.4064)
			(end -0.7874 -0.4064)
			(stroke
				(width 0.1524)
				(type default)
			)
			(layer "F.SilkS")
		)
		(fp_line
			(start -0.7874 -0.4064)
			(end 0.7874 -0.4064)
			(stroke
				(width 0.1524)
				(type default)
			)
			(layer "F.SilkS")
		)
		(fp_line
			(start 0.67945 0.3048)
			(end 0.120396 0.3048)
			(stroke
				(width 0.1)
				(type default)
			)
			(layer "F.Fab")
		)
		(fp_line
			(start 0.67945 -0.3048)
			(end 0.67945 0.3048)
			(stroke
				(width 0.1)
				(type default)
			)
			(layer "F.Fab")
		)
		(fp_line
			(start 0.12065 -0.2794)
			(end 0.12065 -0.3048)
			(stroke
				(width 0.1)
				(type default)
			)
			(layer "F.Fab")
		)
		(fp_line
			(start 0.12065 -0.3048)
			(end 0.67945 -0.3048)
			(stroke
				(width 0.1)
				(type default)
			)
			(layer "F.Fab")
		)
		(fp_line
			(start 0.120396 0.3048)
			(end 0.120396 0.2794)
			(stroke
				(width 0.1)
				(type default)
			)
			(layer "F.Fab")
		)
		(fp_line
			(start 0.120396 0.2794)
			(end -0.12065 0.2794)
			(stroke
				(width 0.1)
				(type default)
			)
			(layer "F.Fab")
		)
		(fp_line
			(start -0.12065 0.3048)
			(end -0.67945 0.3048)
			(stroke
				(width 0.1)
				(type default)
			)
			(layer "F.Fab")
		)
		(fp_line
			(start -0.12065 0.2794)
			(end -0.12065 0.3048)
			(stroke
				(width 0.1)
				(type default)
			)
			(layer "F.Fab")
		)
		(fp_line
			(start -0.12065 -0.2794)
			(end 0.12065 -0.2794)
			(stroke
				(width 0.1)
				(type default)
			)
			(layer "F.Fab")
		)
		(fp_line
			(start -0.12065 -0.305054)
			(end -0.12065 -0.2794)
			(stroke
				(width 0.1)
				(type default)
			)
			(layer "F.Fab")
		)
		(fp_line
			(start -0.67945 0.3048)
			(end -0.67945 -0.305054)
			(stroke
				(width 0.1)
				(type default)
			)
			(layer "F.Fab")
		)
		(fp_line
			(start -0.67945 -0.305054)
			(end -0.12065 -0.305054)
			(stroke
				(width 0.1)
				(type default)
			)
			(layer "F.Fab")
		)
		(pad "1" smd circle
			(at -0.40005 0 180)
			(size 0 0)
			(layers "F.Cu" "F.Mask" "F.Paste")
			(net "GND")
		)
		(pad "2" smd circle
			(at 0.40005 0 180)
			(size 0 0)
			(layers "F.Cu" "F.Mask" "F.Paste")
			(net "P3V3_NIC6")
		)
	)
)
